FILE_TYPE = MACRO_DRAWING;
SET COLOR_WIRE YELLOW;
SET COLOR_PROP ORANGE;
SET COLOR_DOT WHITE;
SET COLOR_ARC YELLOW;
SET COLOR_BODY GREEN;
SET COLOR_NOTE PURPLE;
SET PROP_DISPLAY VALUE;
SET PAGE_NUMBER P123;
FORCEADD QUANTA_TITLE_BLOCK_C..1
(-100 100);
FORCEPROP 1 LAST CUSTOM_TXT_CDS <NAME_2>
J 0
(-3275 150);
FORCEPROP 1 LAST CUSTOM_TXT_CDS <NAME_1>
J 0
(-3275 275);
FORCEPROP 1 LAST CUSTOM_TXT_CDS <Q_NUMBER>
J 0
(-1503 203);
DISPLAY 1.212766 (-1503 203);
FORCEPROP 1 LAST CUSTOM_TXT_CDS <Q_PROJ>
J 0
(-2482 202);
DISPLAY 1.212766 (-2482 202);
FORCEPROP 1 LAST CUSTOM_TXT_CDS <Q_REV>
J 0
(-284 203);
DISPLAY 1.212766 (-284 203);
FORCEPROP 1 LAST CUSTOM_TXT_CDS <CON_LAST_MODIFIED>
J 0
(-1985 115);
DISPLAY 0.978723 (-1985 115);
FORCEPROP 1 LAST CUSTOM_TXT_CDS <CON_PAGE_NUM> OF <CON_TOTAL_PAGES>
J 0
(-546 118);
DISPLAY 0.978723 (-546 118);
FORCEPROP 1 LAST Q_TITLE OCP 3.0 - NCSI/RMII
J 0
(-9375 175);
DISPLAY 2.446809 (-9375 175);
PAINT GREEN (-9375 175);
FORCEPROP 1 LAST Q_DEPT BU9
J 1
(-3863 149);
DISPLAY 1.957447 (-3863 149);
PAINT GREEN (-3863 149);
FORCEPROP 2 LAST PAGE_BORDER TRUE
J 0
(-7990 5350);
DISPLAY 0.638298 (-7990 5350);
PAINT PINK (-7990 5350);
DISPLAY INVISIBLE (-7990 5350);
FORCEPROP 1 LAST CDS_LMAN_SYM_OUTLINE -9475,6775,100,-125
J 0
(-100 100);
DISPLAY 0.468085 (-100 100);
PAINT GREEN (-100 100);
DISPLAY INVISIBLE (-100 100);
FORCEPROP 2 LAST CDS_LIB pure_quanta
J 0
(-100 100);
DISPLAY INVISIBLE (-100 100);
FORCEPROP 1 LAST COMMENT_BODY TRUE
J 0
(-88 87);
DISPLAY 0.978723 (-88 87);
PAINT GREEN (-88 87);
DISPLAY INVISIBLE (-88 87);
FORCEPROP 2 LAST CDS_XR_PAGE_TITLE CR-123 : @T6G_MB_LIB.T6G(SCH_1):PAGE123
J 0
(-7990 5350);
DISPLAY 0.638298 (-7990 5350);
PAINT PINK (-7990 5350);
DISPLAY INVISIBLE (-7990 5350);
FORCEPROP 2 LAST CUSTOM_TXT_CDS <XR_PAGE_TITLE>
J 0
(-7990 5350);
DISPLAY 0.638298 (-7990 5350);
PAINT PINK (-7990 5350);
DISPLAY INVISIBLE (-7990 5350);
FORCEPROP 0 LAST CDS_CON_LAST_MODIFIED Wed Mar 09 17:54:58 2022
J 0
(-1985 115);
DISPLAY INVISIBLE (-1985 115);
QUIT
